# T6G (Grand Teton) — schematic netlist excerpt (pin names and nets, part order shuffled) for the footprints in the layout excerpt that follows; sources: Cadence DE-HDL packaged netlist, KiCad conversion of 04192023_DAF0TMB3IC0_F0TG_MB_C_brd_V02_OCP.brd

C6748  Q_CAP_DIFFBUS  DIFF BUS_0.22UF 6.3V 20% X6S  pkg C0201  page 352 : \1\ = P5E_CPU1_P3_TX_BUF_C_DN<11> ; \2\ = P5E_CPU1_P3_TX_BUF_DN<11>
PR276  Q_RES  2.2 1% CHIP  pkg 0402LF  page 222 : A = PVDDCR_CPU1_P1_PVCC ; B = PVDDIO_P1_VCC2
C2377  Q_CAP  22UF 4V 20% X6S  pkg C0402  page 73 : A = PVDDCR_CPU1_P1 ; B = GND

(kicad_pcb
	(version 20260206)
	(generator "pcbnew")
	(generator_version "10.0")
	(general
		(thickness 1.6)
		(legacy_teardrops no)
	)
	(paper "A4")
	(title_block
		(title "04192023_DAF0TMB3IC0_F0TG_MB_C_brd_V02_OCP.brd")
		(comment 1 "Grand Teton / footprints 6914-6916 of 8354")
	)
	(layers
		(0 "F.Cu" signal "TOP")
		(4 "In1.Cu" signal "GND")
		(6 "In2.Cu" signal "IN1")
		(8 "In3.Cu" signal "GND1")
		(10 "In4.Cu" signal "IN2")
		(12 "In5.Cu" signal "GND2")
		(14 "In6.Cu" signal "IN3")
		(16 "In7.Cu" signal "GND3")
		(18 "In8.Cu" signal "VCC")
		(20 "In9.Cu" signal "VCC1")
		(22 "In10.Cu" signal "GND4")
		(24 "In11.Cu" signal "IN4")
		(26 "In12.Cu" signal "GND5")
		(28 "In13.Cu" signal "IN5")
		(30 "In14.Cu" signal "GND6")
		(32 "In15.Cu" signal "IN6")
		(34 "In16.Cu" signal "GND7")
		(2 "B.Cu" signal "BOTTOM")
		(9 "F.Adhes" user "F.Adhesive")
		(11 "B.Adhes" user "B.Adhesive")
		(13 "F.Paste" user "Package Geometry/Pastemask Top")
		(15 "B.Paste" user "Package Geometry/Pastemask Bottom")
		(5 "F.SilkS" user "Ref Des/Silkscreen Top")
		(7 "B.SilkS" user "Ref Des/Silkscreen Bottom")
		(1 "F.Mask" user "Board Geometry/Soldermask Top")
		(3 "B.Mask" user "Board Geometry/Soldermask Bottom")
		(17 "Dwgs.User" user "User.Drawings")
		(19 "Cmts.User" user "User.Comments")
		(21 "Eco1.User" user "User.Eco1")
		(23 "Eco2.User" user "User.Eco2")
		(25 "Edge.Cuts" user "Board Geometry/Outline")
		(27 "Margin" user)
		(31 "F.CrtYd" user "Package Geometry/Place Bound Top")
		(29 "B.CrtYd" user "Package Geometry/Place Bound Bottom")
		(35 "F.Fab" user "Ref Des/Assembly Top")
		(33 "B.Fab" user "Ref Des/Assembly Bottom")
	)
	(footprint ""
		(layer "B.Cu")
		(at 112.054386 -267.529564 -90)
		(property "Reference" "C2377"
			(at 0 0 90)
			(layer "B.SilkS")
			(hide yes)
			(effects
				(font
					(size 1.27 1.27)
				)
				(justify mirror)
			)
		)
		(property "Value" ""
			(at 0 0 90)
			(layer "B.Fab")
			(effects
				(font
					(size 1.27 1.27)
				)
				(justify mirror)
			)
		)
		(duplicate_pad_numbers_are_jumpers no)
		(fp_line
			(start -0.7874 0.4064)
			(end 0.7874 0.4064)
			(stroke
				(width 0.1524)
				(type default)
			)
			(layer "B.SilkS")
		)
		(fp_line
			(start 0.7874 0.4064)
			(end 0.7874 -0.4064)
			(stroke
				(width 0.1524)
				(type default)
			)
			(layer "B.SilkS")
		)
		(fp_line
			(start -0.7874 -0.4064)
			(end -0.7874 0.4064)
			(stroke
				(width 0.1524)
				(type default)
			)
			(layer "B.SilkS")
		)
		(fp_line
			(start 0.7874 -0.4064)
			(end -0.7874 -0.4064)
			(stroke
				(width 0.1524)
				(type default)
			)
			(layer "B.SilkS")
		)
		(fp_line
			(start -0.67945 0.3048)
			(end -0.120396 0.3048)
			(stroke
				(width 0.1)
				(type default)
			)
			(layer "B.Fab")
		)
		(fp_line
			(start -0.120396 0.3048)
			(end -0.120396 0.2794)
			(stroke
				(width 0.1)
				(type default)
			)
			(layer "B.Fab")
		)
		(fp_line
			(start 0.12065 0.3048)
			(end 0.67945 0.3048)
			(stroke
				(width 0.1)
				(type default)
			)
			(layer "B.Fab")
		)
		(fp_line
			(start 0.67945 0.3048)
			(end 0.67945 -0.305054)
			(stroke
				(width 0.1)
				(type default)
			)
			(layer "B.Fab")
		)
		(fp_line
			(start -0.120396 0.2794)
			(end 0.12065 0.2794)
			(stroke
				(width 0.1)
				(type default)
			)
			(layer "B.Fab")
		)
		(fp_line
			(start 0.12065 0.2794)
			(end 0.12065 0.3048)
			(stroke
				(width 0.1)
				(type default)
			)
			(layer "B.Fab")
		)
		(fp_line
			(start -0.12065 -0.2794)
			(end -0.12065 -0.3048)
			(stroke
				(width 0.1)
				(type default)
			)
			(layer "B.Fab")
		)
		(fp_line
			(start 0.12065 -0.2794)
			(end -0.12065 -0.2794)
			(stroke
				(width 0.1)
				(type default)
			)
			(layer "B.Fab")
		)
		(fp_line
			(start -0.67945 -0.3048)
			(end -0.67945 0.3048)
			(stroke
				(width 0.1)
				(type default)
			)
			(layer "B.Fab")
		)
		(fp_line
			(start -0.12065 -0.3048)
			(end -0.67945 -0.3048)
			(stroke
				(width 0.1)
				(type default)
			)
			(layer "B.Fab")
		)
		(fp_line
			(start 0.12065 -0.305054)
			(end 0.12065 -0.2794)
			(stroke
				(width 0.1)
				(type default)
			)
			(layer "B.Fab")
		)
		(fp_line
			(start 0.67945 -0.305054)
			(end 0.12065 -0.305054)
			(stroke
				(width 0.1)
				(type default)
			)
			(layer "B.Fab")
		)
		(pad "1" smd circle
			(at 0.40005 0 90)
			(size 0 0)
			(layers "B.Cu" "B.Mask" "B.Paste")
			(net "PVDDCR_CPU1_P1")
		)
		(pad "2" smd circle
			(at -0.40005 0 90)
			(size 0 0)
			(layers "B.Cu" "B.Mask" "B.Paste")
			(net "GND")
		)
	)
	(footprint ""
		(layer "B.Cu")
		(at 150.095966 -408.517344 90)
		(property "Reference" "C6748"
			(at 0 0 90)
			(layer "B.SilkS")
			(hide yes)
			(effects
				(font
					(size 1.27 1.27)
				)
				(justify mirror)
			)
		)
		(property "Value" ""
			(at 0 0 90)
			(layer "B.Fab")
			(effects
				(font
					(size 1.27 1.27)
				)
				(justify mirror)
			)
		)
		(duplicate_pad_numbers_are_jumpers no)
		(fp_line
			(start 0.299974 -0.150114)
			(end -0.299974 -0.150114)
			(stroke
				(width 0.1)
				(type default)
			)
			(layer "B.Fab")
		)
		(fp_line
			(start -0.299974 -0.150114)
			(end -0.299974 0.150114)
			(stroke
				(width 0.1)
				(type default)
			)
			(layer "B.Fab")
		)
		(fp_line
			(start 0.299974 0.150114)
			(end 0.299974 -0.150114)
			(stroke
				(width 0.1)
				(type default)
			)
			(layer "B.Fab")
		)
		(fp_line
			(start -0.299974 0.150114)
			(end 0.299974 0.150114)
			(stroke
				(width 0.1)
				(type default)
			)
			(layer "B.Fab")
		)
		(pad "1" smd rect
			(at 0.2667 0 270)
			(size 0.3048 0.381)
			(layers "B.Cu" "B.Mask" "B.Paste")
			(net "P5E_CPU1_P3_TX_BUF_C_DN<11>")
		)
		(pad "2" smd rect
			(at -0.2667 0 270)
			(size 0.3048 0.381)
			(layers "B.Cu" "B.Mask" "B.Paste")
			(net "P5E_CPU1_P3_TX_BUF_DN<11>")
		)
	)
	(footprint ""
		(layer "B.Cu")
		(at 42.875962 -347.780356 -90)
		(property "Reference" "PR276"
			(at 0 0 90)
			(layer "B.SilkS")
			(hide yes)
			(effects
				(font
					(size 1.27 1.27)
				)
				(justify mirror)
			)
		)
		(property "Value" ""
			(at 0 0 90)
			(layer "B.Fab")
			(effects
				(font
					(size 1.27 1.27)
				)
				(justify mirror)
			)
		)
		(duplicate_pad_numbers_are_jumpers no)
		(fp_line
			(start -0.7874 0.4064)
			(end 0.7874 0.4064)
			(stroke
				(width 0.1524)
				(type default)
			)
			(layer "B.SilkS")
		)
		(fp_line
			(start 0.7874 0.4064)
			(end 0.7874 -0.4064)
			(stroke
				(width 0.1524)
				(type default)
			)
			(layer "B.SilkS")
		)
		(fp_line
			(start -0.7874 -0.4064)
			(end -0.7874 0.4064)
			(stroke
				(width 0.1524)
				(type default)
			)
			(layer "B.SilkS")
		)
		(fp_line
			(start 0.7874 -0.4064)
			(end -0.7874 -0.4064)
			(stroke
				(width 0.1524)
				(type default)
			)
			(layer "B.SilkS")
		)
		(fp_line
			(start -0.67945 0.3048)
			(end -0.120396 0.3048)
			(stroke
				(width 0.1)
				(type default)
			)
			(layer "B.Fab")
		)
		(fp_line
			(start -0.120396 0.3048)
			(end -0.120396 0.2794)
			(stroke
				(width 0.1)
				(type default)
			)
			(layer "B.Fab")
		)
		(fp_line
			(start 0.12065 0.3048)
			(end 0.67945 0.3048)
			(stroke
				(width 0.1)
				(type default)
			)
			(layer "B.Fab")
		)
		(fp_line
			(start 0.67945 0.3048)
			(end 0.67945 -0.305054)
			(stroke
				(width 0.1)
				(type default)
			)
			(layer "B.Fab")
		)
		(fp_line
			(start -0.120396 0.2794)
			(end 0.12065 0.2794)
			(stroke
				(width 0.1)
				(type default)
			)
			(layer "B.Fab")
		)
		(fp_line
			(start 0.12065 0.2794)
			(end 0.12065 0.3048)
			(stroke
				(width 0.1)
				(type default)
			)
			(layer "B.Fab")
		)
		(fp_line
			(start -0.12065 -0.2794)
			(end -0.12065 -0.3048)
			(stroke
				(width 0.1)
				(type default)
			)
			(layer "B.Fab")
		)
		(fp_line
			(start 0.12065 -0.2794)
			(end -0.12065 -0.2794)
			(stroke
				(width 0.1)
				(type default)
			)
			(layer "B.Fab")
		)
		(fp_line
			(start -0.67945 -0.3048)
			(end -0.67945 0.3048)
			(stroke
				(width 0.1)
				(type default)
			)
			(layer "B.Fab")
		)
		(fp_line
			(start -0.12065 -0.3048)
			(end -0.67945 -0.3048)
			(stroke
				(width 0.1)
				(type default)
			)
			(layer "B.Fab")
		)
		(fp_line
			(start 0.12065 -0.305054)
			(end 0.12065 -0.2794)
			(stroke
				(width 0.1)
				(type default)
			)
			(layer "B.Fab")
		)
		(fp_line
			(start 0.67945 -0.305054)
			(end 0.12065 -0.305054)
			(stroke
				(width 0.1)
				(type default)
			)
			(layer "B.Fab")
		)
		(pad "1" smd circle
			(at 0.40005 0 90)
			(size 0 0)
			(layers "B.Cu" "B.Mask" "B.Paste")
			(net "PVDDCR_CPU1_P1_PVCC")
		)
		(pad "2" smd circle
			(at -0.40005 0 90)
			(size 0 0)
			(layers "B.Cu" "B.Mask" "B.Paste")
			(net "PVDDIO_P1_VCC2")
		)
	)
)
